(kicad_pcb
	(version 20260206)
	(generator "pcbnew")
	(generator_version "10.0")
	(general
		(thickness 1.6)
		(legacy_teardrops no)
	)
	(paper "A4")
	(title_block
		(title "04192023_DAF0TMB3IC0_F0TG_MB_C_brd_V02_OCP.brd")
		(comment 1 "Grand Teton / footprints 7115-7122 of 8354")
	)
	(layers
		(0 "F.Cu" signal "TOP")
		(4 "In1.Cu" signal "GND")
		(6 "In2.Cu" signal "IN1")
		(8 "In3.Cu" signal "GND1")
		(10 "In4.Cu" signal "IN2")
		(12 "In5.Cu" signal "GND2")
		(14 "In6.Cu" signal "IN3")
		(16 "In7.Cu" signal "GND3")
		(18 "In8.Cu" signal "VCC")
		(20 "In9.Cu" signal "VCC1")
		(22 "In10.Cu" signal "GND4")
		(24 "In11.Cu" signal "IN4")
		(26 "In12.Cu" signal "GND5")
		(28 "In13.Cu" signal "IN5")
		(30 "In14.Cu" signal "GND6")
		(32 "In15.Cu" signal "IN6")
		(34 "In16.Cu" signal "GND7")
		(2 "B.Cu" signal "BOTTOM")
		(9 "F.Adhes" user "F.Adhesive")
		(11 "B.Adhes" user "B.Adhesive")
		(13 "F.Paste" user "Package Geometry/Pastemask Top")
		(15 "B.Paste" user "Package Geometry/Pastemask Bottom")
		(5 "F.SilkS" user "Ref Des/Silkscreen Top")
		(7 "B.SilkS" user "Ref Des/Silkscreen Bottom")
		(1 "F.Mask" user "Board Geometry/Soldermask Top")
		(3 "B.Mask" user "Board Geometry/Soldermask Bottom")
		(17 "Dwgs.User" user "User.Drawings")
		(19 "Cmts.User" user "User.Comments")
		(21 "Eco1.User" user "User.Eco1")
		(23 "Eco2.User" user "User.Eco2")
		(25 "Edge.Cuts" user "Board Geometry/Outline")
		(27 "Margin" user)
		(31 "F.CrtYd" user "Package Geometry/Place Bound Top")
		(29 "B.CrtYd" user "Package Geometry/Place Bound Bottom")
		(35 "F.Fab" user "Ref Des/Assembly Top")
		(33 "B.Fab" user "Ref Des/Assembly Bottom")
	)
	(footprint ""
		(layer "B.Cu")
		(at 309.39105 -398.942052 90)
		(property "Reference" "C569"
			(at 0 0 90)
			(layer "B.SilkS")
			(hide yes)
			(effects
				(font
					(size 1.27 1.27)
				)
				(justify mirror)
			)
		)
		(property "Value" ""
			(at 0 0 90)
			(layer "B.Fab")
			(effects
				(font
					(size 1.27 1.27)
				)
				(justify mirror)
			)
		)
		(duplicate_pad_numbers_are_jumpers no)
		(fp_line
			(start 0.7874 -0.4064)
			(end -0.7874 -0.4064)
			(stroke
				(width 0.1524)
				(type default)
			)
			(layer "B.SilkS")
		)
		(fp_line
			(start -0.7874 -0.4064)
			(end -0.7874 0.4064)
			(stroke
				(width 0.1524)
				(type default)
			)
			(layer "B.SilkS")
		)
		(fp_line
			(start 0.7874 0.4064)
			(end 0.7874 -0.4064)
			(stroke
				(width 0.1524)
				(type default)
			)
			(layer "B.SilkS")
		)
		(fp_line
			(start -0.7874 0.4064)
			(end 0.7874 0.4064)
			(stroke
				(width 0.1524)
				(type default)
			)
			(layer "B.SilkS")
		)
		(fp_line
			(start 0.67945 -0.305054)
			(end 0.12065 -0.305054)
			(stroke
				(width 0.1)
				(type default)
			)
			(layer "B.Fab")
		)
		(fp_line
			(start 0.12065 -0.305054)
			(end 0.12065 -0.2794)
			(stroke
				(width 0.1)
				(type default)
			)
			(layer "B.Fab")
		)
		(fp_line
			(start -0.12065 -0.3048)
			(end -0.67945 -0.3048)
			(stroke
				(width 0.1)
				(type default)
			)
			(layer "B.Fab")
		)
		(fp_line
			(start -0.67945 -0.3048)
			(end -0.67945 0.3048)
			(stroke
				(width 0.1)
				(type default)
			)
			(layer "B.Fab")
		)
		(fp_line
			(start 0.12065 -0.2794)
			(end -0.12065 -0.2794)
			(stroke
				(width 0.1)
				(type default)
			)
			(layer "B.Fab")
		)
		(fp_line
			(start -0.12065 -0.2794)
			(end -0.12065 -0.3048)
			(stroke
				(width 0.1)
				(type default)
			)
			(layer "B.Fab")
		)
		(fp_line
			(start 0.12065 0.2794)
			(end 0.12065 0.3048)
			(stroke
				(width 0.1)
				(type default)
			)
			(layer "B.Fab")
		)
		(fp_line
			(start -0.120396 0.2794)
			(end 0.12065 0.2794)
			(stroke
				(width 0.1)
				(type default)
			)
			(layer "B.Fab")
		)
		(fp_line
			(start 0.67945 0.3048)
			(end 0.67945 -0.305054)
			(stroke
				(width 0.1)
				(type default)
			)
			(layer "B.Fab")
		)
		(fp_line
			(start 0.12065 0.3048)
			(end 0.67945 0.3048)
			(stroke
				(width 0.1)
				(type default)
			)
			(layer "B.Fab")
		)
		(fp_line
			(start -0.120396 0.3048)
			(end -0.120396 0.2794)
			(stroke
				(width 0.1)
				(type default)
			)
			(layer "B.Fab")
		)
		(fp_line
			(start -0.67945 0.3048)
			(end -0.120396 0.3048)
			(stroke
				(width 0.1)
				(type default)
			)
			(layer "B.Fab")
		)
		(pad "1" smd circle
			(at 0.40005 0 270)
			(size 0 0)
			(layers "B.Cu" "B.Mask" "B.Paste")
			(net "P0V9_CPU0_RT_2D")
		)
		(pad "2" smd circle
			(at -0.40005 0 270)
			(size 0 0)
			(layers "B.Cu" "B.Mask" "B.Paste")
			(net "GND")
		)
	)
	(footprint ""
		(layer "B.Cu")
		(at 199.941942 -346.023184)
		(property "Reference" "PC8000"
			(at 0 0 0)
			(layer "B.SilkS")
			(hide yes)
			(effects
				(font
					(size 1.27 1.27)
				)
				(justify mirror)
			)
		)
		(property "Value" ""
			(at 0 0 0)
			(layer "B.Fab")
			(effects
				(font
					(size 1.27 1.27)
				)
				(justify mirror)
			)
		)
		(duplicate_pad_numbers_are_jumpers no)
		(fp_line
			(start -1.524 -0.762)
			(end -1.524 0.762)
			(stroke
				(width 0.1524)
				(type default)
			)
			(layer "B.SilkS")
		)
		(fp_line
			(start -1.524 0.762)
			(end 1.524 0.762)
			(stroke
				(width 0.1524)
				(type default)
			)
			(layer "B.SilkS")
		)
		(fp_line
			(start 1.524 -0.762)
			(end -1.524 -0.762)
			(stroke
				(width 0.1524)
				(type default)
			)
			(layer "B.SilkS")
		)
		(fp_line
			(start 1.524 0.762)
			(end 1.524 -0.762)
			(stroke
				(width 0.1524)
				(type default)
			)
			(layer "B.SilkS")
		)
		(fp_line
			(start -1.1049 -0.724916)
			(end 1.1049 -0.724916)
			(stroke
				(width 0.1)
				(type default)
			)
			(layer "B.Fab")
		)
		(fp_line
			(start -1.1049 0.724916)
			(end -1.1049 -0.724916)
			(stroke
				(width 0.1)
				(type default)
			)
			(layer "B.Fab")
		)
		(fp_line
			(start 1.1049 -0.724916)
			(end 1.1049 0.724916)
			(stroke
				(width 0.1)
				(type default)
			)
			(layer "B.Fab")
		)
		(fp_line
			(start 1.1049 0.724916)
			(end -1.1049 0.724916)
			(stroke
				(width 0.1)
				(type default)
			)
			(layer "B.Fab")
		)
		(pad "1" smd rect
			(at 0.889 0)
			(size 1.016 1.27)
			(layers "B.Cu" "B.Mask" "B.Paste")
			(net "SW_P12V_AUX_PVDD_33_S5_FLT")
		)
		(pad "2" smd rect
			(at -0.889 0)
			(size 1.016 1.27)
			(layers "B.Cu" "B.Mask" "B.Paste")
			(net "GND")
		)
	)
	(footprint ""
		(layer "B.Cu")
		(at 119.103648 -165.079934 -90)
		(property "Reference" "PC335_2"
			(at 0 0 90)
			(layer "B.SilkS")
			(hide yes)
			(effects
				(font
					(size 1.27 1.27)
				)
				(justify mirror)
			)
		)
		(property "Value" ""
			(at 0 0 90)
			(layer "B.Fab")
			(effects
				(font
					(size 1.27 1.27)
				)
				(justify mirror)
			)
		)
		(duplicate_pad_numbers_are_jumpers no)
		(fp_line
			(start -1.524 0.762)
			(end 1.524 0.762)
			(stroke
				(width 0.1524)
				(type default)
			)
			(layer "B.SilkS")
		)
		(fp_line
			(start 1.524 0.762)
			(end 1.524 -0.762)
			(stroke
				(width 0.1524)
				(type default)
			)
			(layer "B.SilkS")
		)
		(fp_line
			(start -1.524 -0.762)
			(end -1.524 0.762)
			(stroke
				(width 0.1524)
				(type default)
			)
			(layer "B.SilkS")
		)
		(fp_line
			(start 1.524 -0.762)
			(end -1.524 -0.762)
			(stroke
				(width 0.1524)
				(type default)
			)
			(layer "B.SilkS")
		)
		(fp_line
			(start -1.1049 0.724916)
			(end -1.1049 -0.724916)
			(stroke
				(width 0.1)
				(type default)
			)
			(layer "B.Fab")
		)
		(fp_line
			(start 1.1049 0.724916)
			(end -1.1049 0.724916)
			(stroke
				(width 0.1)
				(type default)
			)
			(layer "B.Fab")
		)
		(fp_line
			(start -1.1049 -0.724916)
			(end 1.1049 -0.724916)
			(stroke
				(width 0.1)
				(type default)
			)
			(layer "B.Fab")
		)
		(fp_line
			(start 1.1049 -0.724916)
			(end 1.1049 0.724916)
			(stroke
				(width 0.1)
				(type default)
			)
			(layer "B.Fab")
		)
		(pad "1" smd rect
			(at 0.889 0 270)
			(size 1.016 1.27)
			(layers "B.Cu" "B.Mask" "B.Paste")
			(net "SW_P12V_AUX_PVDDCR_SOC_P1_FLT")
		)
		(pad "2" smd rect
			(at -0.889 0 270)
			(size 1.016 1.27)
			(layers "B.Cu" "B.Mask" "B.Paste")
			(net "GND")
		)
	)
	(footprint ""
		(layer "B.Cu")
		(at 218.066112 -67.661028 90)
		(property "Reference" "R83"
			(at 0 0 90)
			(layer "B.SilkS")
			(hide yes)
			(effects
				(font
					(size 1.27 1.27)
				)
				(justify mirror)
			)
		)
		(property "Value" ""
			(at 0 0 90)
			(layer "B.Fab")
			(effects
				(font
					(size 1.27 1.27)
				)
				(justify mirror)
			)
		)
		(duplicate_pad_numbers_are_jumpers no)
		(fp_line
			(start 0.7874 -0.4064)
			(end -0.7874 -0.4064)
			(stroke
				(width 0.1524)
				(type default)
			)
			(layer "B.SilkS")
		)
		(fp_line
			(start -0.7874 -0.4064)
			(end -0.7874 0.4064)
			(stroke
				(width 0.1524)
				(type default)
			)
			(layer "B.SilkS")
		)
		(fp_line
			(start 0.7874 0.4064)
			(end 0.7874 -0.4064)
			(stroke
				(width 0.1524)
				(type default)
			)
			(layer "B.SilkS")
		)
		(fp_line
			(start -0.7874 0.4064)
			(end 0.7874 0.4064)
			(stroke
				(width 0.1524)
				(type default)
			)
			(layer "B.SilkS")
		)
		(fp_line
			(start 0.67945 -0.305054)
			(end 0.12065 -0.305054)
			(stroke
				(width 0.1)
				(type default)
			)
			(layer "B.Fab")
		)
		(fp_line
			(start 0.12065 -0.305054)
			(end 0.12065 -0.2794)
			(stroke
				(width 0.1)
				(type default)
			)
			(layer "B.Fab")
		)
		(fp_line
			(start -0.12065 -0.3048)
			(end -0.67945 -0.3048)
			(stroke
				(width 0.1)
				(type default)
			)
			(layer "B.Fab")
		)
		(fp_line
			(start -0.67945 -0.3048)
			(end -0.67945 0.3048)
			(stroke
				(width 0.1)
				(type default)
			)
			(layer "B.Fab")
		)
		(fp_line
			(start 0.12065 -0.2794)
			(end -0.12065 -0.2794)
			(stroke
				(width 0.1)
				(type default)
			)
			(layer "B.Fab")
		)
		(fp_line
			(start -0.12065 -0.2794)
			(end -0.12065 -0.3048)
			(stroke
				(width 0.1)
				(type default)
			)
			(layer "B.Fab")
		)
		(fp_line
			(start 0.12065 0.2794)
			(end 0.12065 0.3048)
			(stroke
				(width 0.1)
				(type default)
			)
			(layer "B.Fab")
		)
		(fp_line
			(start -0.120396 0.2794)
			(end 0.12065 0.2794)
			(stroke
				(width 0.1)
				(type default)
			)
			(layer "B.Fab")
		)
		(fp_line
			(start 0.67945 0.3048)
			(end 0.67945 -0.305054)
			(stroke
				(width 0.1)
				(type default)
			)
			(layer "B.Fab")
		)
		(fp_line
			(start 0.12065 0.3048)
			(end 0.67945 0.3048)
			(stroke
				(width 0.1)
				(type default)
			)
			(layer "B.Fab")
		)
		(fp_line
			(start -0.120396 0.3048)
			(end -0.120396 0.2794)
			(stroke
				(width 0.1)
				(type default)
			)
			(layer "B.Fab")
		)
		(fp_line
			(start -0.67945 0.3048)
			(end -0.120396 0.3048)
			(stroke
				(width 0.1)
				(type default)
			)
			(layer "B.Fab")
		)
		(pad "1" smd circle
			(at 0.40005 0 270)
			(size 0 0)
			(layers "B.Cu" "B.Mask" "B.Paste")
			(net "RMII_BMC_OCP_TXD_0")
		)
		(pad "2" smd circle
			(at -0.40005 0 270)
			(size 0 0)
			(layers "B.Cu" "B.Mask" "B.Paste")
			(net "GND")
		)
	)
	(footprint ""
		(layer "B.Cu")
		(at 373.202454 -267.498576)
		(property "Reference" "C2223"
			(at 0 0 0)
			(layer "B.SilkS")
			(hide yes)
			(effects
				(font
					(size 1.27 1.27)
				)
				(justify mirror)
			)
		)
		(property "Value" ""
			(at 0 0 0)
			(layer "B.Fab")
			(effects
				(font
					(size 1.27 1.27)
				)
				(justify mirror)
			)
		)
		(duplicate_pad_numbers_are_jumpers no)
		(fp_line
			(start -0.7874 -0.4064)
			(end -0.7874 0.4064)
			(stroke
				(width 0.1524)
				(type default)
			)
			(layer "B.SilkS")
		)
		(fp_line
			(start -0.7874 0.4064)
			(end 0.7874 0.4064)
			(stroke
				(width 0.1524)
				(type default)
			)
			(layer "B.SilkS")
		)
		(fp_line
			(start 0.7874 -0.4064)
			(end -0.7874 -0.4064)
			(stroke
				(width 0.1524)
				(type default)
			)
			(layer "B.SilkS")
		)
		(fp_line
			(start 0.7874 0.4064)
			(end 0.7874 -0.4064)
			(stroke
				(width 0.1524)
				(type default)
			)
			(layer "B.SilkS")
		)
		(fp_line
			(start -0.67945 -0.3048)
			(end -0.67945 0.3048)
			(stroke
				(width 0.1)
				(type default)
			)
			(layer "B.Fab")
		)
		(fp_line
			(start -0.67945 0.3048)
			(end -0.120396 0.3048)
			(stroke
				(width 0.1)
				(type default)
			)
			(layer "B.Fab")
		)
		(fp_line
			(start -0.12065 -0.3048)
			(end -0.67945 -0.3048)
			(stroke
				(width 0.1)
				(type default)
			)
			(layer "B.Fab")
		)
		(fp_line
			(start -0.12065 -0.2794)
			(end -0.12065 -0.3048)
			(stroke
				(width 0.1)
				(type default)
			)
			(layer "B.Fab")
		)
		(fp_line
			(start -0.120396 0.2794)
			(end 0.12065 0.2794)
			(stroke
				(width 0.1)
				(type default)
			)
			(layer "B.Fab")
		)
		(fp_line
			(start -0.120396 0.3048)
			(end -0.120396 0.2794)
			(stroke
				(width 0.1)
				(type default)
			)
			(layer "B.Fab")
		)
		(fp_line
			(start 0.12065 -0.305054)
			(end 0.12065 -0.2794)
			(stroke
				(width 0.1)
				(type default)
			)
			(layer "B.Fab")
		)
		(fp_line
			(start 0.12065 -0.2794)
			(end -0.12065 -0.2794)
			(stroke
				(width 0.1)
				(type default)
			)
			(layer "B.Fab")
		)
		(fp_line
			(start 0.12065 0.2794)
			(end 0.12065 0.3048)
			(stroke
				(width 0.1)
				(type default)
			)
			(layer "B.Fab")
		)
		(fp_line
			(start 0.12065 0.3048)
			(end 0.67945 0.3048)
			(stroke
				(width 0.1)
				(type default)
			)
			(layer "B.Fab")
		)
		(fp_line
			(start 0.67945 -0.305054)
			(end 0.12065 -0.305054)
			(stroke
				(width 0.1)
				(type default)
			)
			(layer "B.Fab")
		)
		(fp_line
			(start 0.67945 0.3048)
			(end 0.67945 -0.305054)
			(stroke
				(width 0.1)
				(type default)
			)
			(layer "B.Fab")
		)
		(pad "1" smd circle
			(at 0.40005 0 180)
			(size 0 0)
			(layers "B.Cu" "B.Mask" "B.Paste")
			(net "PVDDCR_CPU1_P0")
		)
		(pad "2" smd circle
			(at -0.40005 0 180)
			(size 0 0)
			(layers "B.Cu" "B.Mask" "B.Paste")
			(net "GND")
		)
	)
	(footprint ""
		(layer "B.Cu")
		(at 372.251986 -214.523828 90)
		(property "Reference" "R4535"
			(at 0 0 90)
			(layer "B.SilkS")
			(hide yes)
			(effects
				(font
					(size 1.27 1.27)
				)
				(justify mirror)
			)
		)
		(property "Value" ""
			(at 0 0 90)
			(layer "B.Fab")
			(effects
				(font
					(size 1.27 1.27)
				)
				(justify mirror)
			)
		)
		(duplicate_pad_numbers_are_jumpers no)
		(fp_line
			(start 0.512572 -0.4064)
			(end -0.351028 -0.4064)
			(stroke
				(width 0.1524)
				(type default)
			)
			(layer "B.SilkS")
		)
		(fp_line
			(start -0.7874 0.061214)
			(end -0.7874 0.4064)
			(stroke
				(width 0.1524)
				(type default)
			)
			(layer "B.SilkS")
		)
		(fp_line
			(start 0.7874 0.4064)
			(end 0.7874 0.061214)
			(stroke
				(width 0.1524)
				(type default)
			)
			(layer "B.SilkS")
		)
		(fp_line
			(start -0.7874 0.4064)
			(end 0.7874 0.4064)
			(stroke
				(width 0.1524)
				(type default)
			)
			(layer "B.SilkS")
		)
		(fp_line
			(start 0.67945 -0.305054)
			(end 0.12065 -0.305054)
			(stroke
				(width 0.1)
				(type default)
			)
			(layer "B.Fab")
		)
		(fp_line
			(start 0.12065 -0.305054)
			(end 0.12065 -0.2794)
			(stroke
				(width 0.1)
				(type default)
			)
			(layer "B.Fab")
		)
		(fp_line
			(start -0.12065 -0.3048)
			(end -0.67945 -0.3048)
			(stroke
				(width 0.1)
				(type default)
			)
			(layer "B.Fab")
		)
		(fp_line
			(start -0.67945 -0.3048)
			(end -0.67945 0.3048)
			(stroke
				(width 0.1)
				(type default)
			)
			(layer "B.Fab")
		)
		(fp_line
			(start 0.12065 -0.2794)
			(end -0.12065 -0.2794)
			(stroke
				(width 0.1)
				(type default)
			)
			(layer "B.Fab")
		)
		(fp_line
			(start -0.12065 -0.2794)
			(end -0.12065 -0.3048)
			(stroke
				(width 0.1)
				(type default)
			)
			(layer "B.Fab")
		)
		(fp_line
			(start 0.12065 0.2794)
			(end 0.12065 0.3048)
			(stroke
				(width 0.1)
				(type default)
			)
			(layer "B.Fab")
		)
		(fp_line
			(start -0.120396 0.2794)
			(end 0.12065 0.2794)
			(stroke
				(width 0.1)
				(type default)
			)
			(layer "B.Fab")
		)
		(fp_line
			(start 0.67945 0.3048)
			(end 0.67945 -0.305054)
			(stroke
				(width 0.1)
				(type default)
			)
			(layer "B.Fab")
		)
		(fp_line
			(start 0.12065 0.3048)
			(end 0.67945 0.3048)
			(stroke
				(width 0.1)
				(type default)
			)
			(layer "B.Fab")
		)
		(fp_line
			(start -0.120396 0.3048)
			(end -0.120396 0.2794)
			(stroke
				(width 0.1)
				(type default)
			)
			(layer "B.Fab")
		)
		(fp_line
			(start -0.67945 0.3048)
			(end -0.120396 0.3048)
			(stroke
				(width 0.1)
				(type default)
			)
			(layer "B.Fab")
		)
		(pad "1" smd circle
			(at 0.40005 0 270)
			(size 0 0)
			(layers "B.Cu" "B.Mask" "B.Paste")
			(net "CLK_100M_CPU0_CLK01_R_DP")
		)
		(pad "2" smd circle
			(at -0.40005 0 270)
			(size 0 0)
			(layers "B.Cu" "B.Mask" "B.Paste")
			(net "CLK_100M_CPU0_CLK01_DP")
		)
	)
	(footprint ""
		(layer "B.Cu")
		(at 336.279744 -154.256486 180)
		(property "Reference" "PC261"
			(at 0 0 0)
			(layer "B.SilkS")
			(hide yes)
			(effects
				(font
					(size 1.27 1.27)
				)
				(justify mirror)
			)
		)
		(property "Value" ""
			(at 0 0 0)
			(layer "B.Fab")
			(effects
				(font
					(size 1.27 1.27)
				)
				(justify mirror)
			)
		)
		(duplicate_pad_numbers_are_jumpers no)
		(fp_line
			(start 1.524 0.762)
			(end 1.524 -0.762)
			(stroke
				(width 0.1524)
				(type default)
			)
			(layer "B.SilkS")
		)
		(fp_line
			(start 1.524 -0.762)
			(end -1.524 -0.762)
			(stroke
				(width 0.1524)
				(type default)
			)
			(layer "B.SilkS")
		)
		(fp_line
			(start -1.524 0.762)
			(end 1.524 0.762)
			(stroke
				(width 0.1524)
				(type default)
			)
			(layer "B.SilkS")
		)
		(fp_line
			(start -1.524 -0.762)
			(end -1.524 0.762)
			(stroke
				(width 0.1524)
				(type default)
			)
			(layer "B.SilkS")
		)
		(fp_line
			(start 1.1049 0.724916)
			(end -1.1049 0.724916)
			(stroke
				(width 0.1)
				(type default)
			)
			(layer "B.Fab")
		)
		(fp_line
			(start 1.1049 -0.724916)
			(end 1.1049 0.724916)
			(stroke
				(width 0.1)
				(type default)
			)
			(layer "B.Fab")
		)
		(fp_line
			(start -1.1049 0.724916)
			(end -1.1049 -0.724916)
			(stroke
				(width 0.1)
				(type default)
			)
			(layer "B.Fab")
		)
		(fp_line
			(start -1.1049 -0.724916)
			(end 1.1049 -0.724916)
			(stroke
				(width 0.1)
				(type default)
			)
			(layer "B.Fab")
		)
		(pad "1" smd rect
			(at 0.889 0 180)
			(size 1.016 1.27)
			(layers "B.Cu" "B.Mask" "B.Paste")
			(net "PVDD18_S5_P0")
		)
		(pad "2" smd rect
			(at -0.889 0 180)
			(size 1.016 1.27)
			(layers "B.Cu" "B.Mask" "B.Paste")
			(net "GND")
		)
	)
	(footprint ""
		(layer "B.Cu")
		(at 86.04631 -388.011162 -90)
		(property "Reference" "C290"
			(at 0 0 90)
			(layer "B.SilkS")
			(hide yes)
			(effects
				(font
					(size 1.27 1.27)
				)
				(justify mirror)
			)
		)
		(property "Value" ""
			(at 0 0 90)
			(layer "B.Fab")
			(effects
				(font
					(size 1.27 1.27)
				)
				(justify mirror)
			)
		)
		(duplicate_pad_numbers_are_jumpers no)
		(fp_line
			(start -0.299974 0.150114)
			(end 0.299974 0.150114)
			(stroke
				(width 0.1)
				(type default)
			)
			(layer "B.Fab")
		)
		(fp_line
			(start 0.299974 0.150114)
			(end 0.299974 -0.150114)
			(stroke
				(width 0.1)
				(type default)
			)
			(layer "B.Fab")
		)
		(fp_line
			(start -0.299974 -0.150114)
			(end -0.299974 0.150114)
			(stroke
				(width 0.1)
				(type default)
			)
			(layer "B.Fab")
		)
		(fp_line
			(start 0.299974 -0.150114)
			(end -0.299974 -0.150114)
			(stroke
				(width 0.1)
				(type default)
			)
			(layer "B.Fab")
		)
		(pad "1" smd rect
			(at 0.2667 0 90)
			(size 0.3048 0.381)
			(layers "B.Cu" "B.Mask" "B.Paste")
			(net "P0V9_CPU1_RT_2D")
		)
		(pad "2" smd rect
			(at -0.2667 0 90)
			(size 0.3048 0.381)
			(layers "B.Cu" "B.Mask" "B.Paste")
			(net "GND")
		)
	)
)
